FILE_TYPE=LIBRARY_PARTS;
primitive 'MOSFET_PCH_GDS_ESD_PROTECTED';
  pin
    'D':
      PIN_NUMBER='(D)';
      BIDIRECTIONAL='TRUE';
      INPUT_LOAD='(-0.01,0.01)';
      OUTPUT_LOAD='(1.0,-1.0)';
    'G':
      PIN_NUMBER='(G)';
      INPUT_LOAD='(-0.01,0.01)';
    'S':
      PIN_NUMBER='(S)';
      BIDIRECTIONAL='TRUE';
      INPUT_LOAD='(-0.01,0.01)';
      OUTPUT_LOAD='(1.0,-1.0)';
  end_pin;
  body
    PART_NAME='MOSFET_PCH_GDS_ESD_PROTECTED';
    BODY_NAME='MOSFET_PCH_GDS_ESD_PROTECTED';
    PHYS_DES_PREFIX='Q';
    CLASS='DISCRETE';
  end_body;
end_primitive;

END.
